FILE_TYPE=LIBRARY_PARTS;
primitive '74LVC1G07W57';
  pin
    'VCC':
      PIN_NUMBER='(5)';
      PINUSE='POWER';
      NO_LOAD_CHECK='Both';
      NO_IO_CHECK='Both';
      NO_ASSERT_CHECK='TRUE';
      NO_DIR_CHECK='TRUE';
      ALLOW_CONNECT='TRUE';
    'A':
      PIN_NUMBER='(2)';
      INPUT_LOAD='(-0.01,0.01)';
    'GND':
      PIN_NUMBER='(3)';
      PINUSE='POWER';
      NO_LOAD_CHECK='Both';
      NO_IO_CHECK='Both';
      NO_ASSERT_CHECK='TRUE';
      NO_DIR_CHECK='TRUE';
      ALLOW_CONNECT='TRUE';
    'Y':
      PIN_NUMBER='(4)';
      OUTPUT_TYPE='(OC,AND)';
      OUTPUT_LOAD='(1.0,*)';
    'NC1':
      PIN_NUMBER='(1)';
      OUTPUT_TYPE='(TS,TS)';
      INPUT_LOAD='(-0.01,0.01)';
      OUTPUT_LOAD='(1.0,-1.0)';
  end_pin;
  body
    PART_NAME='74LVC1G07W57';
    BODY_NAME='74LVC1G07W57';
    PHYS_DES_PREFIX='U';
    CLASS='IC';
  end_body;
end_primitive;

END.
